(kicad_pcb
	(version 20260206)
	(generator "pcbnew")
	(generator_version "10.0")
	(general
		(thickness 1.6)
		(legacy_teardrops no)
	)
	(paper "A4")
	(title_block
		(title "03242023_DA0F0TMBIJ0_F0T_Motherboard_J_brd_V01_OCP.brd")
		(comment 1 "Grand Teton / footprint 1660 of 6105 (J24), pads 1-112 of 291")
	)
	(layers
		(0 "F.Cu" signal "TOP")
		(4 "In1.Cu" signal "GND")
		(6 "In2.Cu" signal "IN1")
		(8 "In3.Cu" signal "GND1")
		(10 "In4.Cu" signal "IN2")
		(12 "In5.Cu" signal "GND2")
		(14 "In6.Cu" signal "IN3")
		(16 "In7.Cu" signal "GND3")
		(18 "In8.Cu" signal "VCC")
		(20 "In9.Cu" signal "VCC1")
		(22 "In10.Cu" signal "GND4")
		(24 "In11.Cu" signal "IN4")
		(26 "In12.Cu" signal "GND5")
		(28 "In13.Cu" signal "IN5")
		(30 "In14.Cu" signal "GND6")
		(32 "In15.Cu" signal "IN6")
		(34 "In16.Cu" signal "GND7")
		(2 "B.Cu" signal "BOTTOM")
		(9 "F.Adhes" user "F.Adhesive")
		(11 "B.Adhes" user "B.Adhesive")
		(13 "F.Paste" user "Package Geometry/Pastemask Top")
		(15 "B.Paste" user "Package Geometry/Pastemask Bottom")
		(5 "F.SilkS" user "Ref Des/Silkscreen Top")
		(7 "B.SilkS" user "Ref Des/Silkscreen Bottom")
		(1 "F.Mask" user "Board Geometry/Soldermask Top")
		(3 "B.Mask" user "Board Geometry/Soldermask Bottom")
		(17 "Dwgs.User" user "User.Drawings")
		(19 "Cmts.User" user "User.Comments")
		(21 "Eco1.User" user "User.Eco1")
		(23 "Eco2.User" user "User.Eco2")
		(25 "Edge.Cuts" user "Board Geometry/Outline")
		(27 "Margin" user)
		(31 "F.CrtYd" user "Package Geometry/Place Bound Top")
		(29 "B.CrtYd" user "Package Geometry/Place Bound Bottom")
		(35 "F.Fab" user "Ref Des/Assembly Top")
		(33 "B.Fab" user "Ref Des/Assembly Bottom")
	)
	(footprint ""
		(layer "F.Cu")
		(at 17.73428 -258.091686)
		(property "Reference" "J24"
			(at -3.0607 -81.901792 0)
			(unlocked yes)
			(layer "F.SilkS")
			(effects
				(font
					(size 0.7874 0.5842)
					(thickness 0.1524)
				)
				(justify left)
			)
		)
		(property "Value" ""
			(at 0 0 0)
			(layer "F.Fab")
			(effects
				(font
					(size 1.27 1.27)
				)
			)
		)
		(duplicate_pad_numbers_are_jumpers no)
		(pad "1" smd rect
			(at -2.050034 -63.324994 270)
			(size 0.519938 1.4986)
			(layers "F.Cu" "F.Mask" "F.Paste")
			(net "P12V_S3_AUX_CPU1_NVDIMM")
		)
		(pad "2" smd rect
			(at -2.050034 -62.47511 270)
			(size 0.519938 1.4986)
			(layers "F.Cu" "F.Mask" "F.Paste")
			(net "TP_CHD_CPU1_DIMM2_FRU_0")
		)
		(pad "3" smd rect
			(at -2.050034 -61.624972 270)
			(size 0.519938 1.4986)
			(layers "F.Cu" "F.Mask" "F.Paste")
			(net "P3V3_AUX")
		)
		(pad "4" smd rect
			(at -2.050034 -60.775088 270)
			(size 0.519938 1.4986)
			(layers "F.Cu" "F.Mask" "F.Paste")
			(net "I3C_SPD_DDRABCD_CPU1_LVC1_SCL_7")
		)
		(pad "5" smd rect
			(at -2.050034 -59.92495 270)
			(size 0.519938 1.4986)
			(layers "F.Cu" "F.Mask" "F.Paste")
			(net "I3C_SPD_DDRABCD_CPU1_LVC1_SDA")
		)
		(pad "6" smd rect
			(at -2.050034 -59.075066 270)
			(size 0.519938 1.4986)
			(layers "F.Cu" "F.Mask" "F.Paste")
			(net "GND")
		)
		(pad "7" smd rect
			(at -2.050034 -58.224928 270)
			(size 0.519938 1.4986)
			(layers "F.Cu" "F.Mask" "F.Paste")
			(net "M_D_CPU1_SA_DQ<0>")
		)
		(pad "8" smd rect
			(at -2.050034 -57.375044 270)
			(size 0.519938 1.4986)
			(layers "F.Cu" "F.Mask" "F.Paste")
			(net "GND")
		)
		(pad "9" smd rect
			(at -2.050034 -56.524906 270)
			(size 0.519938 1.4986)
			(layers "F.Cu" "F.Mask" "F.Paste")
			(net "M_D_CPU1_SA_DQ<1>")
		)
		(pad "10" smd rect
			(at -2.050034 -55.675022 270)
			(size 0.519938 1.4986)
			(layers "F.Cu" "F.Mask" "F.Paste")
			(net "GND")
		)
		(pad "11" smd rect
			(at -2.050034 -54.824884 270)
			(size 0.519938 1.4986)
			(layers "F.Cu" "F.Mask" "F.Paste")
			(net "M_D_CPU1_SA_DQS_DP<0>")
		)
		(pad "12" smd rect
			(at -2.050034 -53.975 270)
			(size 0.519938 1.4986)
			(layers "F.Cu" "F.Mask" "F.Paste")
			(net "M_D_CPU1_SA_DQS_DN<0>")
		)
		(pad "13" smd rect
			(at -2.050034 -53.125116 270)
			(size 0.519938 1.4986)
			(layers "F.Cu" "F.Mask" "F.Paste")
			(net "GND")
		)
		(pad "14" smd rect
			(at -2.050034 -52.274978 270)
			(size 0.519938 1.4986)
			(layers "F.Cu" "F.Mask" "F.Paste")
			(net "M_D_CPU1_SA_DQ<4>")
		)
		(pad "15" smd rect
			(at -2.050034 -51.425094 270)
			(size 0.519938 1.4986)
			(layers "F.Cu" "F.Mask" "F.Paste")
			(net "GND")
		)
		(pad "16" smd rect
			(at -2.050034 -50.574956 270)
			(size 0.519938 1.4986)
			(layers "F.Cu" "F.Mask" "F.Paste")
			(net "M_D_CPU1_SA_DQ<5>")
		)
		(pad "17" smd rect
			(at -2.050034 -49.725072 270)
			(size 0.519938 1.4986)
			(layers "F.Cu" "F.Mask" "F.Paste")
			(net "GND")
		)
		(pad "18" smd rect
			(at -2.050034 -48.874934 270)
			(size 0.519938 1.4986)
			(layers "F.Cu" "F.Mask" "F.Paste")
			(net "M_D_CPU1_SA_DQ<8>")
		)
		(pad "19" smd rect
			(at -2.050034 -48.02505 270)
			(size 0.519938 1.4986)
			(layers "F.Cu" "F.Mask" "F.Paste")
			(net "GND")
		)
		(pad "20" smd rect
			(at -2.050034 -47.174912 270)
			(size 0.519938 1.4986)
			(layers "F.Cu" "F.Mask" "F.Paste")
			(net "M_D_CPU1_SA_DQ<9>")
		)
		(pad "21" smd rect
			(at -2.050034 -46.325028 270)
			(size 0.519938 1.4986)
			(layers "F.Cu" "F.Mask" "F.Paste")
			(net "GND")
		)
		(pad "22" smd rect
			(at -2.050034 -45.47489 270)
			(size 0.519938 1.4986)
			(layers "F.Cu" "F.Mask" "F.Paste")
			(net "M_D_CPU1_SA_DQS_DP<1>")
		)
		(pad "23" smd rect
			(at -2.050034 -44.625006 270)
			(size 0.519938 1.4986)
			(layers "F.Cu" "F.Mask" "F.Paste")
			(net "M_D_CPU1_SA_DQS_DN<1>")
		)
		(pad "24" smd rect
			(at -2.050034 -43.775122 270)
			(size 0.519938 1.4986)
			(layers "F.Cu" "F.Mask" "F.Paste")
			(net "GND")
		)
		(pad "25" smd rect
			(at -2.050034 -42.924984 270)
			(size 0.519938 1.4986)
			(layers "F.Cu" "F.Mask" "F.Paste")
			(net "M_D_CPU1_SA_DQ<12>")
		)
		(pad "26" smd rect
			(at -2.050034 -42.0751 270)
			(size 0.519938 1.4986)
			(layers "F.Cu" "F.Mask" "F.Paste")
			(net "GND")
		)
		(pad "27" smd rect
			(at -2.050034 -41.224962 270)
			(size 0.519938 1.4986)
			(layers "F.Cu" "F.Mask" "F.Paste")
			(net "M_D_CPU1_SA_DQ<13>")
		)
		(pad "28" smd rect
			(at -2.050034 -40.375078 270)
			(size 0.519938 1.4986)
			(layers "F.Cu" "F.Mask" "F.Paste")
			(net "GND")
		)
		(pad "29" smd rect
			(at -2.050034 -39.52494 270)
			(size 0.519938 1.4986)
			(layers "F.Cu" "F.Mask" "F.Paste")
			(net "M_D_CPU1_SA_DQ<16>")
		)
		(pad "30" smd rect
			(at -2.050034 -38.675056 270)
			(size 0.519938 1.4986)
			(layers "F.Cu" "F.Mask" "F.Paste")
			(net "GND")
		)
		(pad "31" smd rect
			(at -2.050034 -37.824918 270)
			(size 0.519938 1.4986)
			(layers "F.Cu" "F.Mask" "F.Paste")
			(net "M_D_CPU1_SA_DQ<17>")
		)
		(pad "32" smd rect
			(at -2.050034 -36.975034 270)
			(size 0.519938 1.4986)
			(layers "F.Cu" "F.Mask" "F.Paste")
			(net "GND")
		)
		(pad "33" smd rect
			(at -2.050034 -36.124896 270)
			(size 0.519938 1.4986)
			(layers "F.Cu" "F.Mask" "F.Paste")
			(net "M_D_CPU1_SA_DQS_DP<2>")
		)
		(pad "34" smd rect
			(at -2.050034 -35.275012 270)
			(size 0.519938 1.4986)
			(layers "F.Cu" "F.Mask" "F.Paste")
			(net "M_D_CPU1_SA_DQS_DN<2>")
		)
		(pad "35" smd rect
			(at -2.050034 -34.425128 270)
			(size 0.519938 1.4986)
			(layers "F.Cu" "F.Mask" "F.Paste")
			(net "GND")
		)
		(pad "36" smd rect
			(at -2.050034 -33.57499 270)
			(size 0.519938 1.4986)
			(layers "F.Cu" "F.Mask" "F.Paste")
			(net "M_D_CPU1_SA_DQ<20>")
		)
		(pad "37" smd rect
			(at -2.050034 -32.725106 270)
			(size 0.519938 1.4986)
			(layers "F.Cu" "F.Mask" "F.Paste")
			(net "GND")
		)
		(pad "38" smd rect
			(at -2.050034 -31.874968 270)
			(size 0.519938 1.4986)
			(layers "F.Cu" "F.Mask" "F.Paste")
			(net "M_D_CPU1_SA_DQ<21>")
		)
		(pad "39" smd rect
			(at -2.050034 -31.025084 270)
			(size 0.519938 1.4986)
			(layers "F.Cu" "F.Mask" "F.Paste")
			(net "GND")
		)
		(pad "40" smd rect
			(at -2.050034 -30.174946 270)
			(size 0.519938 1.4986)
			(layers "F.Cu" "F.Mask" "F.Paste")
			(net "M_D_CPU1_SA_DQ<24>")
		)
		(pad "41" smd rect
			(at -2.050034 -29.325062 270)
			(size 0.519938 1.4986)
			(layers "F.Cu" "F.Mask" "F.Paste")
			(net "GND")
		)
		(pad "42" smd rect
			(at -2.050034 -28.474924 270)
			(size 0.519938 1.4986)
			(layers "F.Cu" "F.Mask" "F.Paste")
			(net "M_D_CPU1_SA_DQ<25>")
		)
		(pad "43" smd rect
			(at -2.050034 -27.62504 270)
			(size 0.519938 1.4986)
			(layers "F.Cu" "F.Mask" "F.Paste")
			(net "GND")
		)
		(pad "44" smd rect
			(at -2.050034 -26.774902 270)
			(size 0.519938 1.4986)
			(layers "F.Cu" "F.Mask" "F.Paste")
			(net "M_D_CPU1_SA_DQS_DP<3>")
		)
		(pad "45" smd rect
			(at -2.050034 -25.925018 270)
			(size 0.519938 1.4986)
			(layers "F.Cu" "F.Mask" "F.Paste")
			(net "M_D_CPU1_SA_DQS_DN<3>")
		)
		(pad "46" smd rect
			(at -2.050034 -25.07488 270)
			(size 0.519938 1.4986)
			(layers "F.Cu" "F.Mask" "F.Paste")
			(net "GND")
		)
		(pad "47" smd rect
			(at -2.050034 -24.224996 270)
			(size 0.519938 1.4986)
			(layers "F.Cu" "F.Mask" "F.Paste")
			(net "M_D_CPU1_SA_DQ<28>")
		)
		(pad "48" smd rect
			(at -2.050034 -23.375112 270)
			(size 0.519938 1.4986)
			(layers "F.Cu" "F.Mask" "F.Paste")
			(net "GND")
		)
		(pad "49" smd rect
			(at -2.050034 -22.524974 270)
			(size 0.519938 1.4986)
			(layers "F.Cu" "F.Mask" "F.Paste")
			(net "M_D_CPU1_SA_DQ<29>")
		)
		(pad "50" smd rect
			(at -2.050034 -21.67509 270)
			(size 0.519938 1.4986)
			(layers "F.Cu" "F.Mask" "F.Paste")
			(net "GND")
		)
		(pad "51" smd rect
			(at -2.050034 -20.824952 270)
			(size 0.519938 1.4986)
			(layers "F.Cu" "F.Mask" "F.Paste")
			(net "M_D_CPU1_SA_CB<0>")
		)
		(pad "52" smd rect
			(at -2.050034 -19.975068 270)
			(size 0.519938 1.4986)
			(layers "F.Cu" "F.Mask" "F.Paste")
			(net "GND")
		)
		(pad "53" smd rect
			(at -2.050034 -19.12493 270)
			(size 0.519938 1.4986)
			(layers "F.Cu" "F.Mask" "F.Paste")
			(net "M_D_CPU1_SA_CB<1>")
		)
		(pad "54" smd rect
			(at -2.050034 -18.275046 270)
			(size 0.519938 1.4986)
			(layers "F.Cu" "F.Mask" "F.Paste")
			(net "GND")
		)
		(pad "55" smd rect
			(at -2.050034 -17.424908 270)
			(size 0.519938 1.4986)
			(layers "F.Cu" "F.Mask" "F.Paste")
			(net "M_D_CPU1_SA_DQS_DP<4>")
		)
		(pad "56" smd rect
			(at -2.050034 -16.575024 270)
			(size 0.519938 1.4986)
			(layers "F.Cu" "F.Mask" "F.Paste")
			(net "M_D_CPU1_SA_DQS_DN<4>")
		)
		(pad "57" smd rect
			(at -2.050034 -15.724886 270)
			(size 0.519938 1.4986)
			(layers "F.Cu" "F.Mask" "F.Paste")
			(net "GND")
		)
		(pad "58" smd rect
			(at -2.050034 -14.875002 270)
			(size 0.519938 1.4986)
			(layers "F.Cu" "F.Mask" "F.Paste")
			(net "M_D_CPU1_SA_CB<4>")
		)
		(pad "59" smd rect
			(at -2.050034 -14.025118 270)
			(size 0.519938 1.4986)
			(layers "F.Cu" "F.Mask" "F.Paste")
			(net "GND")
		)
		(pad "60" smd rect
			(at -2.050034 -13.17498 270)
			(size 0.519938 1.4986)
			(layers "F.Cu" "F.Mask" "F.Paste")
			(net "M_D_CPU1_SA_CB<5>")
		)
		(pad "61" smd rect
			(at -2.050034 -12.325096 270)
			(size 0.519938 1.4986)
			(layers "F.Cu" "F.Mask" "F.Paste")
			(net "GND")
		)
		(pad "62" smd rect
			(at -2.050034 -11.474958 270)
			(size 0.519938 1.4986)
			(layers "F.Cu" "F.Mask" "F.Paste")
			(net "M_D_CPU1_ALERT_N")
		)
		(pad "63" smd rect
			(at -2.050034 -10.625074 270)
			(size 0.519938 1.4986)
			(layers "F.Cu" "F.Mask" "F.Paste")
			(net "GND")
		)
		(pad "64" smd rect
			(at -2.050034 -9.774936 270)
			(size 0.519938 1.4986)
			(layers "F.Cu" "F.Mask" "F.Paste")
			(net "M_D_CPU1_SA_CS_N<2>")
		)
		(pad "65" smd rect
			(at -2.050034 -8.925052 270)
			(size 0.519938 1.4986)
			(layers "F.Cu" "F.Mask" "F.Paste")
			(net "GND")
		)
		(pad "66" smd rect
			(at -2.050034 -8.074914 270)
			(size 0.519938 1.4986)
			(layers "F.Cu" "F.Mask" "F.Paste")
			(net "M_D_CPU1_SA_CA<0>")
		)
		(pad "67" smd rect
			(at -2.050034 -7.22503 270)
			(size 0.519938 1.4986)
			(layers "F.Cu" "F.Mask" "F.Paste")
			(net "GND")
		)
		(pad "68" smd rect
			(at -2.050034 -6.374892 270)
			(size 0.519938 1.4986)
			(layers "F.Cu" "F.Mask" "F.Paste")
			(net "M_D_CPU1_SA_CA<2>")
		)
		(pad "69" smd rect
			(at -2.050034 -5.525008 270)
			(size 0.519938 1.4986)
			(layers "F.Cu" "F.Mask" "F.Paste")
			(net "GND")
		)
		(pad "70" smd rect
			(at -2.050034 -4.675124 270)
			(size 0.519938 1.4986)
			(layers "F.Cu" "F.Mask" "F.Paste")
			(net "M_D_CPU1_SA_CA<4>")
		)
		(pad "71" smd rect
			(at -2.050034 -3.824986 270)
			(size 0.519938 1.4986)
			(layers "F.Cu" "F.Mask" "F.Paste")
			(net "GND")
		)
		(pad "72" smd rect
			(at -2.050034 -2.975102 270)
			(size 0.519938 1.4986)
			(layers "F.Cu" "F.Mask" "F.Paste")
			(net "M_D_CPU1_SA_CA<6>")
		)
		(pad "73" smd rect
			(at -2.050034 -2.124964 270)
			(size 0.519938 1.4986)
			(layers "F.Cu" "F.Mask" "F.Paste")
			(net "GND")
		)
		(pad "74" smd rect
			(at -2.050034 -1.27508 270)
			(size 0.519938 1.4986)
			(layers "F.Cu" "F.Mask" "F.Paste")
			(net "M_D_CPU1_SA_PAR")
		)
		(pad "75" smd rect
			(at -2.050034 -0.424942 270)
			(size 0.519938 1.4986)
			(layers "F.Cu" "F.Mask" "F.Paste")
			(net "GND")
		)
		(pad "76" smd rect
			(at -2.050034 5.525008 270)
			(size 0.519938 1.4986)
			(layers "F.Cu" "F.Mask" "F.Paste")
			(net "M_D_CPU1_SB_CA<0>")
		)
		(pad "77" smd rect
			(at -2.050034 6.374892 270)
			(size 0.519938 1.4986)
			(layers "F.Cu" "F.Mask" "F.Paste")
			(net "GND")
		)
		(pad "78" smd rect
			(at -2.050034 7.22503 270)
			(size 0.519938 1.4986)
			(layers "F.Cu" "F.Mask" "F.Paste")
			(net "M_D_CPU1_SB_CA<2>")
		)
		(pad "79" smd rect
			(at -2.050034 8.074914 270)
			(size 0.519938 1.4986)
			(layers "F.Cu" "F.Mask" "F.Paste")
			(net "GND")
		)
		(pad "80" smd rect
			(at -2.050034 8.925052 270)
			(size 0.519938 1.4986)
			(layers "F.Cu" "F.Mask" "F.Paste")
			(net "M_D_CPU1_SB_CA<4>")
		)
		(pad "81" smd rect
			(at -2.050034 9.774936 270)
			(size 0.519938 1.4986)
			(layers "F.Cu" "F.Mask" "F.Paste")
			(net "GND")
		)
		(pad "82" smd rect
			(at -2.050034 10.625074 270)
			(size 0.519938 1.4986)
			(layers "F.Cu" "F.Mask" "F.Paste")
			(net "M_D_CPU1_SB_CA<6>")
		)
		(pad "83" smd rect
			(at -2.050034 11.474958 270)
			(size 0.519938 1.4986)
			(layers "F.Cu" "F.Mask" "F.Paste")
			(net "GND")
		)
		(pad "84" smd rect
			(at -2.050034 12.325096 270)
			(size 0.519938 1.4986)
			(layers "F.Cu" "F.Mask" "F.Paste")
			(net "M_D_CPU1_SB_CS_N<2>")
		)
		(pad "85" smd rect
			(at -2.050034 13.17498 270)
			(size 0.519938 1.4986)
			(layers "F.Cu" "F.Mask" "F.Paste")
			(net "GND")
		)
		(pad "86" smd rect
			(at -2.050034 14.025118 270)
			(size 0.519938 1.4986)
			(layers "F.Cu" "F.Mask" "F.Paste")
			(net "M_D_CPU1_SA_RSP<1>")
		)
		(pad "87" smd rect
			(at -2.050034 14.875002 270)
			(size 0.519938 1.4986)
			(layers "F.Cu" "F.Mask" "F.Paste")
			(net "M_D_CPU1_SB_RSP<1>")
		)
		(pad "88" smd rect
			(at -2.050034 15.724886 270)
			(size 0.519938 1.4986)
			(layers "F.Cu" "F.Mask" "F.Paste")
			(net "GND")
		)
		(pad "89" smd rect
			(at -2.050034 16.575024 270)
			(size 0.519938 1.4986)
			(layers "F.Cu" "F.Mask" "F.Paste")
			(net "M_D_CPU1_SB_CB<4>")
		)
		(pad "90" smd rect
			(at -2.050034 17.424908 270)
			(size 0.519938 1.4986)
			(layers "F.Cu" "F.Mask" "F.Paste")
			(net "GND")
		)
		(pad "91" smd rect
			(at -2.050034 18.275046 270)
			(size 0.519938 1.4986)
			(layers "F.Cu" "F.Mask" "F.Paste")
			(net "M_D_CPU1_SB_CB<5>")
		)
		(pad "92" smd rect
			(at -2.050034 19.12493 270)
			(size 0.519938 1.4986)
			(layers "F.Cu" "F.Mask" "F.Paste")
			(net "GND")
		)
		(pad "93" smd rect
			(at -2.050034 19.975068 270)
			(size 0.519938 1.4986)
			(layers "F.Cu" "F.Mask" "F.Paste")
			(net "M_D_CPU1_SB_DQS_DP<9>")
		)
		(pad "94" smd rect
			(at -2.050034 20.824952 270)
			(size 0.519938 1.4986)
			(layers "F.Cu" "F.Mask" "F.Paste")
			(net "M_D_CPU1_SB_DQS_DN<9>")
		)
		(pad "95" smd rect
			(at -2.050034 21.67509 270)
			(size 0.519938 1.4986)
			(layers "F.Cu" "F.Mask" "F.Paste")
			(net "GND")
		)
		(pad "96" smd rect
			(at -2.050034 22.524974 270)
			(size 0.519938 1.4986)
			(layers "F.Cu" "F.Mask" "F.Paste")
			(net "M_D_CPU1_SB_CB<0>")
		)
		(pad "97" smd rect
			(at -2.050034 23.375112 270)
			(size 0.519938 1.4986)
			(layers "F.Cu" "F.Mask" "F.Paste")
			(net "GND")
		)
		(pad "98" smd rect
			(at -2.050034 24.224996 270)
			(size 0.519938 1.4986)
			(layers "F.Cu" "F.Mask" "F.Paste")
			(net "M_D_CPU1_SB_CB<1>")
		)
		(pad "99" smd rect
			(at -2.050034 25.07488 270)
			(size 0.519938 1.4986)
			(layers "F.Cu" "F.Mask" "F.Paste")
			(net "GND")
		)
		(pad "100" smd rect
			(at -2.050034 25.925018 270)
			(size 0.519938 1.4986)
			(layers "F.Cu" "F.Mask" "F.Paste")
			(net "M_D_CPU1_SB_DQ<0>")
		)
		(pad "101" smd rect
			(at -2.050034 26.774902 270)
			(size 0.519938 1.4986)
			(layers "F.Cu" "F.Mask" "F.Paste")
			(net "GND")
		)
		(pad "102" smd rect
			(at -2.050034 27.62504 270)
			(size 0.519938 1.4986)
			(layers "F.Cu" "F.Mask" "F.Paste")
			(net "M_D_CPU1_SB_DQ<1>")
		)
		(pad "103" smd rect
			(at -2.050034 28.474924 270)
			(size 0.519938 1.4986)
			(layers "F.Cu" "F.Mask" "F.Paste")
			(net "GND")
		)
		(pad "104" smd rect
			(at -2.050034 29.325062 270)
			(size 0.519938 1.4986)
			(layers "F.Cu" "F.Mask" "F.Paste")
			(net "M_D_CPU1_SB_DQS_DP<0>")
		)
		(pad "105" smd rect
			(at -2.050034 30.174946 270)
			(size 0.519938 1.4986)
			(layers "F.Cu" "F.Mask" "F.Paste")
			(net "M_D_CPU1_SB_DQS_DN<0>")
		)
		(pad "106" smd rect
			(at -2.050034 31.025084 270)
			(size 0.519938 1.4986)
			(layers "F.Cu" "F.Mask" "F.Paste")
			(net "GND")
		)
		(pad "107" smd rect
			(at -2.050034 31.874968 270)
			(size 0.519938 1.4986)
			(layers "F.Cu" "F.Mask" "F.Paste")
			(net "M_D_CPU1_SB_DQ<4>")
		)
		(pad "108" smd rect
			(at -2.050034 32.725106 270)
			(size 0.519938 1.4986)
			(layers "F.Cu" "F.Mask" "F.Paste")
			(net "GND")
		)
		(pad "109" smd rect
			(at -2.050034 33.57499 270)
			(size 0.519938 1.4986)
			(layers "F.Cu" "F.Mask" "F.Paste")
			(net "M_D_CPU1_SB_DQ<5>")
		)
		(pad "110" smd rect
			(at -2.050034 34.425128 270)
			(size 0.519938 1.4986)
			(layers "F.Cu" "F.Mask" "F.Paste")
			(net "GND")
		)
		(pad "111" smd rect
			(at -2.050034 35.275012 270)
			(size 0.519938 1.4986)
			(layers "F.Cu" "F.Mask" "F.Paste")
			(net "M_D_CPU1_SB_DQ<8>")
		)
		(pad "112" smd rect
			(at -2.050034 36.124896 270)
			(size 0.519938 1.4986)
			(layers "F.Cu" "F.Mask" "F.Paste")
			(net "GND")
		)
	)
)
